(kicad_pcb
	(version 20241229)
	(generator "pcbnew")
	(generator_version "9.0")
	(general
		(thickness 1.61)
		(legacy_teardrops no)
	)
	(paper "A3")
	(title_block
		(title "RDIMM DDR5 Tester")
		(date "2026-05-21")
		(rev "2.2.0")
		(company "Antmicro")
		(comment 9 "footprints 53-56 of 796")
	)
	(layers
		(0 "F.Cu" signal)
		(4 "In1.Cu" power)
		(6 "In2.Cu" mixed)
		(8 "In3.Cu" power)
		(10 "In4.Cu" mixed)
		(12 "In5.Cu" power)
		(14 "In6.Cu" mixed)
		(16 "In7.Cu" power)
		(18 "In8.Cu" power)
		(20 "In9.Cu" mixed)
		(22 "In10.Cu" power)
		(2 "B.Cu" signal)
		(9 "F.Adhes" user "F.Adhesive")
		(11 "B.Adhes" user "B.Adhesive")
		(13 "F.Paste" user)
		(15 "B.Paste" user)
		(5 "F.SilkS" user "F.Silkscreen")
		(7 "B.SilkS" user "B.Silkscreen")
		(1 "F.Mask" user)
		(3 "B.Mask" user)
		(17 "Dwgs.User" user "User.Drawings")
		(19 "Cmts.User" user "User.Comments")
		(21 "Eco1.User" user "User.Eco1")
		(23 "Eco2.User" user "User.Eco2")
		(25 "Edge.Cuts" user)
		(27 "Margin" user)
		(31 "F.CrtYd" user "F.Courtyard")
		(29 "B.CrtYd" user "B.Courtyard")
		(35 "F.Fab" user)
		(33 "B.Fab" user)
	)
	(footprint "antmicro-footprints:C_0603_1608Metric"
		(layer "F.Cu")
		(at 257.149499 150.171)
		(descr "Capacitor SMD 0603")
		(tags "capacitor 0603")
		(property "Reference" "C192"
			(at 1.200501 0.529 0)
			(layer "F.SilkS")
			(effects
				(font
					(size 0.7 0.7)
					(thickness 0.15)
				)
				(justify left bottom)
			)
		)
		(property "Value" "C_22u_0603"
			(at -1.42757 1.770288 0)
			(layer "F.Fab")
			(effects
				(font
					(size 0.7 0.7)
					(thickness 0.15)
				)
				(justify left bottom)
			)
		)
		(property "Datasheet" "https://www.murata.com/products/productdetail?partno=GRM188R60J226MEA0%23"
			(at 0 0 0)
			(layer "F.Fab")
			(hide yes)
			(effects
				(font
					(size 1.27 1.27)
					(thickness 0.15)
				)
			)
		)
		(property "Manufacturer" "Murata"
			(at 0 0 0)
			(unlocked yes)
			(layer "F.Fab")
			(hide yes)
			(effects
				(font
					(size 1 1)
					(thickness 0.15)
				)
			)
		)
		(property "MPN" "GRM188R60J226MEA0D"
			(at 0 0 0)
			(unlocked yes)
			(layer "F.Fab")
			(hide yes)
			(effects
				(font
					(size 1 1)
					(thickness 0.15)
				)
			)
		)
		(property "Val" "22u"
			(at 0 0 0)
			(unlocked yes)
			(layer "F.Fab")
			(hide yes)
			(effects
				(font
					(size 1 1)
					(thickness 0.15)
				)
			)
		)
		(property "License" "Apache-2.0"
			(at 0 0 0)
			(unlocked yes)
			(layer "F.Fab")
			(hide yes)
			(effects
				(font
					(size 1 1)
					(thickness 0.15)
				)
			)
		)
		(property "Author" "Antmicro"
			(at 0 0 0)
			(unlocked yes)
			(layer "F.Fab")
			(hide yes)
			(effects
				(font
					(size 1 1)
					(thickness 0.15)
				)
			)
		)
		(property "Voltage" ""
			(at 0 0 0)
			(unlocked yes)
			(layer "F.Fab")
			(hide yes)
			(effects
				(font
					(size 1 1)
					(thickness 0.15)
				)
			)
		)
		(property "Dielectric" ""
			(at 0 0 0)
			(unlocked yes)
			(layer "F.Fab")
			(hide yes)
			(effects
				(font
					(size 1 1)
					(thickness 0.15)
				)
			)
		)
		(sheetname "/Supply/DC-DC IO/")
		(sheetfile "dc-dc-io.kicad_sch")
		(attr smd)
		(fp_line
			(start -0.15 -0.4)
			(end 0.15 -0.4)
			(stroke
				(width 0.15)
				(type solid)
			)
			(layer "F.SilkS")
		)
		(fp_line
			(start -0.15 0.4)
			(end 0.15 0.4)
			(stroke
				(width 0.15)
				(type solid)
			)
			(layer "F.SilkS")
		)
		(fp_rect
			(start -1.25 -0.65)
			(end 1.25 0.65)
			(stroke
				(width 0.05)
				(type solid)
			)
			(fill no)
			(layer "F.CrtYd")
		)
		(fp_rect
			(start -0.8 -0.4)
			(end 0.8 0.4)
			(stroke
				(width 0.15)
				(type solid)
			)
			(fill no)
			(layer "F.Fab")
		)
		(fp_text user "${REFERENCE}"
			(at -1.682 3.895 0)
			(layer "F.Fab")
			(effects
				(font
					(size 0.7 0.7)
					(thickness 0.15)
				)
				(justify left bottom)
			)
		)
		(fp_text user "License: Apache-2.0"
			(at -1.682 5.895 0)
			(layer "F.Fab")
			(effects
				(font
					(size 0.7 0.7)
					(thickness 0.15)
				)
				(justify left bottom)
			)
		)
		(fp_text user "Author: Antmicro"
			(at -1.682 4.894 0)
			(layer "F.Fab")
			(effects
				(font
					(size 0.7 0.7)
					(thickness 0.15)
				)
				(justify left bottom)
			)
		)
		(pad "1" smd roundrect
			(at -0.7 0)
			(size 0.8 1)
			(layers "F.Cu" "F.Mask" "F.Paste")
			(roundrect_rratio 0.2)
			(net 1 "GND")
			(pintype "passive")
		)
		(pad "2" smd roundrect
			(at 0.7 0)
			(size 0.8 1)
			(layers "F.Cu" "F.Mask" "F.Paste")
			(roundrect_rratio 0.2)
			(net 158 "/Supply/DC-DC IO/VDDQ_local")
			(pintype "passive")
		)
	)
	(footprint "antmicro-footprints:USON-10_2.5x1mm_P0.5mm"
		(layer "F.Cu")
		(at 113.530499 179.5525 180)
		(descr "USON-10 2.5x1mm_ Pitch 0.5mm")
		(tags "USON-10 2.5x1mm Pitch 0.5mm")
		(property "Reference" "U11"
			(at -1.819501 0.7025 90)
			(layer "F.SilkS")
			(effects
				(font
					(size 0.7 0.7)
					(thickness 0.15)
				)
				(justify right bottom)
			)
		)
		(property "Value" "TPD4E05U06QDQARQ1"
			(at 0.018 2.499 0)
			(layer "F.Fab")
			(effects
				(font
					(size 0.7 0.7)
					(thickness 0.15)
				)
				(justify right bottom)
			)
		)
		(property "Datasheet" "https://www.ti.com/lit/ds/symlink/tpd4e05u06-q1.pdf?HQS=dis-mous-null-mousermode-dsf-pf-null-wwe&ts=1663591265741&ref_url=https%253A%252F%252Fwww.mouser.com%252F"
			(at 0 0 180)
			(layer "F.Fab")
			(hide yes)
			(effects
				(font
					(size 1.27 1.27)
					(thickness 0.15)
				)
			)
		)
		(property "Manufacturer" "Texas Instruments"
			(at 0 0 180)
			(unlocked yes)
			(layer "F.Fab")
			(hide yes)
			(effects
				(font
					(size 1 1)
					(thickness 0.15)
				)
			)
		)
		(property "MPN" "TPD4E05U06QDQARQ1"
			(at 0 0 180)
			(unlocked yes)
			(layer "F.Fab")
			(hide yes)
			(effects
				(font
					(size 1 1)
					(thickness 0.15)
				)
			)
		)
		(property "Author" "Antmicro"
			(at 0 0 180)
			(unlocked yes)
			(layer "F.Fab")
			(hide yes)
			(effects
				(font
					(size 1 1)
					(thickness 0.15)
				)
			)
		)
		(property "License" "Apache-2.0"
			(at 0 0 180)
			(unlocked yes)
			(layer "F.Fab")
			(hide yes)
			(effects
				(font
					(size 1 1)
					(thickness 0.15)
				)
			)
		)
		(sheetname "/HDMI + SD Card/")
		(sheetfile "hdmi-sd-card.kicad_sch")
		(attr smd)
		(fp_line
			(start 0.498 1.398)
			(end -0.5 1.398)
			(stroke
				(width 0.15)
				(type solid)
			)
			(layer "F.SilkS")
		)
		(fp_line
			(start 0.498 -1.401)
			(end -0.5 -1.401)
			(stroke
				(width 0.15)
				(type solid)
			)
			(layer "F.SilkS")
		)
		(fp_circle
			(center -0.68 -1.27)
			(end -0.63 -1.27)
			(stroke
				(width 0.15)
				(type solid)
			)
			(fill yes)
			(layer "F.SilkS")
		)
		(fp_rect
			(start -0.8 -1.5)
			(end 0.8 1.499)
			(stroke
				(width 0.05)
				(type solid)
			)
			(fill no)
			(layer "F.CrtYd")
		)
		(fp_line
			(start 0.498 -1.25)
			(end 0.498 1.249)
			(stroke
				(width 0.15)
				(type solid)
			)
			(layer "F.Fab")
		)
		(fp_line
			(start 0.498 -1.25)
			(end -0.25 -1.25)
			(stroke
				(width 0.15)
				(type solid)
			)
			(layer "F.Fab")
		)
		(fp_line
			(start -0.25 -1.25)
			(end -0.5 -1)
			(stroke
				(width 0.15)
				(type solid)
			)
			(layer "F.Fab")
		)
		(fp_line
			(start -0.5 1.249)
			(end 0.498 1.249)
			(stroke
				(width 0.15)
				(type solid)
			)
			(layer "F.Fab")
		)
		(fp_line
			(start -0.5 -1)
			(end -0.5 1.249)
			(stroke
				(width 0.15)
				(type solid)
			)
			(layer "F.Fab")
		)
		(fp_text user "License: Apache-2.0"
			(at -0.802 6.9 180)
			(layer "F.Fab")
			(effects
				(font
					(size 0.7 0.7)
					(thickness 0.15)
				)
				(justify left bottom)
			)
		)
		(fp_text user "Author: Antmicro"
			(at -0.802 5.7 180)
			(layer "F.Fab")
			(effects
				(font
					(size 0.7 0.7)
					(thickness 0.15)
				)
				(justify left bottom)
			)
		)
		(fp_text user "${REFERENCE}"
			(at -0.802 4.498 180)
			(layer "F.Fab")
			(effects
				(font
					(size 0.7 0.7)
					(thickness 0.15)
				)
				(justify left bottom)
			)
		)
		(pad "1" smd roundrect
			(at -0.387 -1 90)
			(size 0.25 0.55)
			(layers "F.Cu" "F.Mask" "F.Paste")
			(roundrect_rratio 0.25)
			(net 658 "/HDMI + SD Card/HDMI_OUT_CONN_D0_P")
			(pintype "passive")
		)
		(pad "2" smd roundrect
			(at -0.387 -0.5 90)
			(size 0.25 0.55)
			(layers "F.Cu" "F.Mask" "F.Paste")
			(roundrect_rratio 0.25)
			(net 659 "/HDMI + SD Card/HDMI_OUT_CONN_D0_N")
			(pintype "passive")
		)
		(pad "3" smd roundrect
			(at -0.387 0 90)
			(size 0.4 0.55)
			(layers "F.Cu" "F.Mask" "F.Paste")
			(roundrect_rratio 0.25)
			(net 1 "GND")
			(pintype "power_in")
		)
		(pad "4" smd roundrect
			(at -0.387 0.498 90)
			(size 0.25 0.55)
			(layers "F.Cu" "F.Mask" "F.Paste")
			(roundrect_rratio 0.25)
			(net 660 "/HDMI + SD Card/HDMI_OUT_CONN_CLK_P")
			(pintype "passive")
		)
		(pad "5" smd roundrect
			(at -0.387 0.998 90)
			(size 0.25 0.55)
			(layers "F.Cu" "F.Mask" "F.Paste")
			(roundrect_rratio 0.25)
			(net 661 "/HDMI + SD Card/HDMI_OUT_CONN_CLK_N")
			(pintype "passive")
		)
		(pad "6" smd roundrect
			(at 0.385 0.998 90)
			(size 0.25 0.55)
			(layers "F.Cu" "F.Mask" "F.Paste")
			(roundrect_rratio 0.25)
			(net 661 "/HDMI + SD Card/HDMI_OUT_CONN_CLK_N")
			(pintype "passive")
		)
		(pad "7" smd roundrect
			(at 0.385 0.498 90)
			(size 0.25 0.55)
			(layers "F.Cu" "F.Mask" "F.Paste")
			(roundrect_rratio 0.25)
			(net 660 "/HDMI + SD Card/HDMI_OUT_CONN_CLK_P")
			(pintype "passive")
		)
		(pad "8" smd roundrect
			(at 0.385 0 90)
			(size 0.4 0.55)
			(layers "F.Cu" "F.Mask" "F.Paste")
			(roundrect_rratio 0.25)
			(net 1 "GND")
			(pintype "passive")
		)
		(pad "9" smd roundrect
			(at 0.385 -0.5 90)
			(size 0.25 0.55)
			(layers "F.Cu" "F.Mask" "F.Paste")
			(roundrect_rratio 0.25)
			(net 659 "/HDMI + SD Card/HDMI_OUT_CONN_D0_N")
			(pintype "passive")
		)
		(pad "10" smd roundrect
			(at 0.385 -1 90)
			(size 0.25 0.55)
			(layers "F.Cu" "F.Mask" "F.Paste")
			(roundrect_rratio 0.25)
			(net 658 "/HDMI + SD Card/HDMI_OUT_CONN_D0_P")
			(pintype "passive")
		)
	)
	(footprint "antmicro-footprints:SC70-3"
		(layer "F.Cu")
		(at 250.274499 146)
		(property "Reference" "Q9"
			(at 0.375501 0.75 90)
			(layer "F.SilkS")
			(effects
				(font
					(size 0.7 0.7)
					(thickness 0.15)
				)
				(justify left bottom)
			)
		)
		(property "Value" "BSS138PW"
			(at 0 2.3 0)
			(layer "F.Fab")
			(effects
				(font
					(size 0.7 0.7)
					(thickness 0.15)
				)
				(justify left bottom)
			)
		)
		(property "Datasheet" "https://assets.nexperia.com/documents/data-sheet/BSS138PW.pdf"
			(at 0 0 0)
			(layer "F.Fab")
			(hide yes)
			(effects
				(font
					(size 1.27 1.27)
					(thickness 0.15)
				)
			)
		)
		(property "MPN" "BSS138PW"
			(at 0 0 0)
			(unlocked yes)
			(layer "F.Fab")
			(hide yes)
			(effects
				(font
					(size 1 1)
					(thickness 0.15)
				)
			)
		)
		(property "Manufacturer" "Nexperia"
			(at 0 0 0)
			(unlocked yes)
			(layer "F.Fab")
			(hide yes)
			(effects
				(font
					(size 1 1)
					(thickness 0.15)
				)
			)
		)
		(property "Author" "Antmicro"
			(at 0 0 0)
			(unlocked yes)
			(layer "F.Fab")
			(hide yes)
			(effects
				(font
					(size 1 1)
					(thickness 0.15)
				)
			)
		)
		(property "License" "Apache-2.0"
			(at 0 0 0)
			(unlocked yes)
			(layer "F.Fab")
			(hide yes)
			(effects
				(font
					(size 1 1)
					(thickness 0.15)
				)
			)
		)
		(sheetname "/DDR5 RDIMM/")
		(sheetfile "ddr5-rdimm.kicad_sch")
		(attr smd)
		(fp_line
			(start -0.3 -1)
			(end 0.627 -0.999)
			(stroke
				(width 0.15)
				(type solid)
			)
			(layer "F.SilkS")
		)
		(fp_line
			(start -0.3 1)
			(end 0.627 1.001)
			(stroke
				(width 0.15)
				(type solid)
			)
			(layer "F.SilkS")
		)
		(fp_line
			(start 0.627 -0.6)
			(end 0.627 -0.999)
			(stroke
				(width 0.15)
				(type solid)
			)
			(layer "F.SilkS")
		)
		(fp_line
			(start 0.627 0.6)
			(end 0.627 1.001)
			(stroke
				(width 0.15)
				(type solid)
			)
			(layer "F.SilkS")
		)
		(fp_line
			(start -1.4 1)
			(end -1.4 -1)
			(stroke
				(width 0.05)
				(type solid)
			)
			(layer "F.CrtYd")
		)
		(fp_line
			(start -0.9 -1.3)
			(end -0.9 -1)
			(stroke
				(width 0.05)
				(type solid)
			)
			(layer "F.CrtYd")
		)
		(fp_line
			(start -0.9 -1.3)
			(end 0.9 -1.3)
			(stroke
				(width 0.05)
				(type solid)
			)
			(layer "F.CrtYd")
		)
		(fp_line
			(start -0.9 -1)
			(end -1.4 -1)
			(stroke
				(width 0.05)
				(type solid)
			)
			(layer "F.CrtYd")
		)
		(fp_line
			(start -0.9 1)
			(end -1.4 1)
			(stroke
				(width 0.05)
				(type solid)
			)
			(layer "F.CrtYd")
		)
		(fp_line
			(start -0.9 1.3)
			(end -0.9 1)
			(stroke
				(width 0.05)
				(type solid)
			)
			(layer "F.CrtYd")
		)
		(fp_line
			(start 0.9 -1.3)
			(end 0.9 -0.4)
			(stroke
				(width 0.05)
				(type solid)
			)
			(layer "F.CrtYd")
		)
		(fp_line
			(start 0.9 -0.4)
			(end 1.4 -0.4)
			(stroke
				(width 0.05)
				(type solid)
			)
			(layer "F.CrtYd")
		)
		(fp_line
			(start 0.9 0.4)
			(end 0.9 1.3)
			(stroke
				(width 0.05)
				(type solid)
			)
			(layer "F.CrtYd")
		)
		(fp_line
			(start 0.9 1.3)
			(end -0.9 1.3)
			(stroke
				(width 0.05)
				(type solid)
			)
			(layer "F.CrtYd")
		)
		(fp_line
			(start 1.4 -0.4)
			(end 1.4 0.4)
			(stroke
				(width 0.05)
				(type solid)
			)
			(layer "F.CrtYd")
		)
		(fp_line
			(start 1.4 0.4)
			(end 0.9 0.4)
			(stroke
				(width 0.05)
				(type solid)
			)
			(layer "F.CrtYd")
		)
		(fp_rect
			(start -0.623 -0.999)
			(end 0.627 1.001)
			(stroke
				(width 0.15)
				(type solid)
			)
			(fill no)
			(layer "F.Fab")
		)
		(fp_text user "Author: Antmicro"
			(at -1.45 5.782 0)
			(layer "F.Fab")
			(effects
				(font
					(size 0.7 0.7)
					(thickness 0.15)
				)
				(justify left bottom)
			)
		)
		(fp_text user "License: Apache-2.0"
			(at -1.45 6.782 0)
			(layer "F.Fab")
			(effects
				(font
					(size 0.7 0.7)
					(thickness 0.15)
				)
				(justify left bottom)
			)
		)
		(fp_text user "${REFERENCE}"
			(at -1.45 4.783 0)
			(layer "F.Fab")
			(effects
				(font
					(size 0.7 0.7)
					(thickness 0.15)
				)
				(justify left bottom)
			)
		)
		(pad "1" smd rect
			(at -1.051 -0.65 90)
			(size 0.6 0.6)
			(layers "F.Cu" "F.Mask" "F.Paste")
			(net 179 "HOT_SWAP_YELLOW")
			(pinfunction "G")
			(pintype "passive")
		)
		(pad "2" smd rect
			(at -1.051 0.65 90)
			(size 0.6 0.6)
			(layers "F.Cu" "F.Mask" "F.Paste")
			(net 1 "GND")
			(pinfunction "S")
			(pintype "passive")
		)
		(pad "3" smd rect
			(at 1.05 0 90)
			(size 0.6 0.6)
			(layers "F.Cu" "F.Mask" "F.Paste")
			(net 277 "Net-(Q9-D)")
			(pinfunction "D")
			(pintype "passive")
		)
	)
	(footprint "antmicro-footprints:R_0402_1005Metric"
		(layer "F.Cu")
		(at 116.256 176.367)
		(descr "Resistor SMD 0402")
		(tags "resistor SMD 0402")
		(property "Reference" "R72"
			(at 0.9 0.45 0)
			(layer "F.SilkS")
			(effects
				(font
					(size 0.7 0.7)
					(thickness 0.15)
				)
				(justify left bottom)
			)
		)
		(property "Value" "R_2k2_0402"
			(at -1.011843 1.772047 0)
			(layer "F.Fab")
			(effects
				(font
					(size 0.7 0.7)
					(thickness 0.15)
				)
				(justify left bottom)
			)
		)
		(property "Datasheet" "https://www.bourns.com/docs/product-datasheets/cr.pdf"
			(at 0 0 0)
			(layer "F.Fab")
			(hide yes)
			(effects
				(font
					(size 1.27 1.27)
					(thickness 0.15)
				)
			)
		)
		(property "MPN" "CR0402-FX-2201GLF"
			(at 0 0 0)
			(unlocked yes)
			(layer "F.Fab")
			(hide yes)
			(effects
				(font
					(size 1 1)
					(thickness 0.15)
				)
			)
		)
		(property "Manufacturer" "Bourns"
			(at 0 0 0)
			(unlocked yes)
			(layer "F.Fab")
			(hide yes)
			(effects
				(font
					(size 1 1)
					(thickness 0.15)
				)
			)
		)
		(property "License" "Apache-2.0"
			(at 0 0 0)
			(unlocked yes)
			(layer "F.Fab")
			(hide yes)
			(effects
				(font
					(size 1 1)
					(thickness 0.15)
				)
			)
		)
		(property "Author" "Antmicro"
			(at 0 0 0)
			(unlocked yes)
			(layer "F.Fab")
			(hide yes)
			(effects
				(font
					(size 1 1)
					(thickness 0.15)
				)
			)
		)
		(property "Val" "2k2"
			(at 0 0 0)
			(unlocked yes)
			(layer "F.Fab")
			(hide yes)
			(effects
				(font
					(size 1 1)
					(thickness 0.15)
				)
			)
		)
		(property "Tolerance" "1%"
			(at 0 0 0)
			(unlocked yes)
			(layer "F.Fab")
			(hide yes)
			(effects
				(font
					(size 1 1)
					(thickness 0.15)
				)
			)
		)
		(property "Public" ""
			(at 0 0 0)
			(unlocked yes)
			(layer "F.Fab")
			(hide yes)
			(effects
				(font
					(size 1 1)
					(thickness 0.15)
				)
			)
		)
		(sheetname "/HDMI + SD Card/")
		(sheetfile "hdmi-sd-card.kicad_sch")
		(attr smd)
		(fp_rect
			(start -0.925 -0.47)
			(end 0.925 0.47)
			(stroke
				(width 0.05)
				(type default)
			)
			(fill no)
			(layer "F.CrtYd")
		)
		(fp_rect
			(start -0.5 -0.25)
			(end 0.5 0.25)
			(stroke
				(width 0.15)
				(type solid)
			)
			(fill no)
			(layer "F.Fab")
		)
		(fp_text user "Author: Antmicro"
			(at -0.95 4.169 0)
			(layer "F.Fab")
			(effects
				(font
					(size 0.7 0.7)
					(thickness 0.15)
				)
				(justify left bottom)
			)
		)
		(fp_text user "${REFERENCE}"
			(at -0.95 3.168 0)
			(layer "F.Fab")
			(effects
				(font
					(size 0.7 0.7)
					(thickness 0.15)
				)
				(justify left bottom)
			)
		)
		(fp_text user "License: Apache-2.0"
			(at -0.95 5.169 0)
			(layer "F.Fab")
			(effects
				(font
					(size 0.7 0.7)
					(thickness 0.15)
				)
				(justify left bottom)
			)
		)
		(pad "1" smd roundrect
			(at -0.48 0)
			(size 0.59 0.64)
			(layers "F.Cu" "F.Mask" "F.Paste")
			(roundrect_rratio 0.25)
			(net 468 "/HDMI + SD Card/HDMI_OUT_C.SDA")
			(pintype "passive")
		)
		(pad "2" smd roundrect
			(at 0.48 0)
			(size 0.59 0.64)
			(layers "F.Cu" "F.Mask" "F.Paste")
			(roundrect_rratio 0.25)
			(net 8 "/HDMI + SD Card/HDMI_CONN_5V")
			(pintype "passive")
		)
	)
)
